FILE_TYPE = CONNECTIVITY;
{Allegro Design Entry HDL 17.2-2016 S081 (4005846) 1/11/2022}
"PAGE_NUMBER" = 51;
0"NC";
1"P5E_CPU1_P0_TX_DP<0:15>";
2"P5E_CPU1_P0_TX_DN<0:15>";
3"P5E_CPU1_P1_TX_DN<15:0>";
4"P5E_CPU1_P1_TX_DP<15:0>";
5"P5E_CPU1_P0_RX_DN<0:15>";
6"P5E_CPU1_P0_RX_DP<0:15>";
7"P5E_CPU1_P1_RX_DP<15:0>";
8"P5E_CPU1_P1_RX_DN<15:0>";
9"P5E_CPU1_P1_RX_DN<6>";
10"P5E_CPU1_P1_RX_DP<6>";
11"P5E_CPU1_P0_RX_DN<12>";
12"P5E_CPU1_P0_RX_DP<12>";
13"P5E_CPU1_P0_RX_DN<11>";
14"P5E_CPU1_P0_RX_DP<11>";
15"P5E_CPU1_P0_RX_DP<10>";
16"P5E_CPU1_P0_RX_DP<9>";
17"P5E_CPU1_P0_RX_DN<0>";
18"P5E_CPU1_P0_RX_DP<0>";
19"P5E_CPU1_P1_RX_DN<5>";
20"P5E_CPU1_P1_RX_DP<7>";
21"P5E_CPU1_P1_RX_DN<4>";
22"P5E_CPU1_P1_RX_DN<3>";
23"P5E_CPU1_P1_RX_DP<5>";
24"P5E_CPU1_P1_RX_DN<2>";
25"P5E_CPU1_P1_RX_DP<4>";
26"P5E_CPU1_P1_RX_DN<1>";
27"P5E_CPU1_P1_RX_DP<3>";
28"P5E_CPU1_P1_RX_DN<0>";
29"P5E_CPU1_P1_RX_DP<2>";
30"P5E_CPU1_P1_RX_DP<1>";
31"P5E_CPU1_P1_RX_DP<0>";
32"P5E_CPU1_P1_RX_DN<7>";
33"P5E_CPU1_P1_RX_DN<15>";
34"P5E_CPU1_P1_RX_DP<15>";
35"P5E_CPU1_P1_RX_DN<14>";
36"P5E_CPU1_P1_RX_DP<14>";
37"P5E_CPU1_P1_RX_DN<13>";
38"P5E_CPU1_P1_RX_DP<13>";
39"P5E_CPU1_P1_RX_DN<12>";
40"P5E_CPU1_P1_RX_DP<12>";
41"P5E_CPU1_P1_RX_DN<11>";
42"P5E_CPU1_P1_RX_DP<11>";
43"P5E_CPU1_P1_RX_DN<10>";
44"P5E_CPU1_P1_RX_DP<10>";
45"P5E_CPU1_P1_RX_DN<9>";
46"P5E_CPU1_P1_RX_DP<9>";
47"P5E_CPU1_P1_RX_DN<8>";
48"P5E_CPU1_P1_RX_DP<8>";
49"P5E_CPU1_P0_RX_DN<4>";
50"P5E_CPU1_P0_RX_DP<4>";
51"P5E_CPU1_P0_RX_DP<1>";
52"P5E_CPU1_P0_RX_DN<2>";
53"P5E_CPU1_P0_RX_DN<5>";
54"P5E_CPU1_P0_RX_DP<6>";
55"P5E_CPU1_P0_RX_DP<5>";
56"P5E_CPU1_P0_RX_DP<2>";
57"P5E_CPU1_P0_RX_DN<6>";
58"P5E_CPU1_P0_RX_DN<3>";
59"P5E_CPU1_P0_RX_DP<7>";
60"P5E_CPU1_P0_RX_DP<3>";
61"P5E_CPU1_P0_RX_DN<7>";
62"P5E_CPU1_P0_RX_DN<1>";
63"P5E_CPU1_P0_RX_DN<9>";
64"P5E_CPU1_P0_RX_DN<15>";
65"P5E_CPU1_P0_RX_DP<13>";
66"P5E_CPU1_P0_RX_DN<10>";
67"P5E_CPU1_P0_RX_DN<13>";
68"P5E_CPU1_P0_RX_DP<8>";
69"P5E_CPU1_P0_RX_DP<14>";
70"P5E_CPU1_P0_RX_DN<8>";
71"P5E_CPU1_P0_RX_DN<14>";
72"P5E_CPU1_P0_RX_DP<15>";
73"P5E_CPU1_P1_TX_DP<15>";
74"P5E_CPU1_P1_TX_DP<14>";
75"P5E_CPU1_P1_TX_DP<13>";
76"P5E_CPU1_P1_TX_DP<12>";
77"P5E_CPU1_P1_TX_DP<11>";
78"P5E_CPU1_P1_TX_DP<10>";
79"P5E_CPU1_P1_TX_DP<9>";
80"P5E_CPU1_P1_TX_DN<15>";
81"P5E_CPU1_P1_TX_DN<14>";
82"P5E_CPU1_P1_TX_DN<13>";
83"P5E_CPU1_P1_TX_DN<12>";
84"P5E_CPU1_P1_TX_DN<11>";
85"P5E_CPU1_P1_TX_DN<10>";
86"P5E_CPU1_P1_TX_DN<9>";
87"P5E_CPU1_P1_TX_DP<7>";
88"P5E_CPU1_P1_TX_DP<6>";
89"P5E_CPU1_P1_TX_DP<5>";
90"P5E_CPU1_P1_TX_DP<4>";
91"P5E_CPU1_P1_TX_DP<8>";
92"P5E_CPU1_P1_TX_DP<3>";
93"P5E_CPU1_P1_TX_DP<2>";
94"P5E_CPU1_P1_TX_DP<1>";
95"P5E_CPU1_P1_TX_DP<0>";
96"P5E_CPU1_P0_TX_DP<0>";
97"P5E_CPU1_P0_TX_DN<0>";
98"P5E_CPU1_P1_TX_DN<7>";
99"P5E_CPU1_P1_TX_DN<6>";
100"P5E_CPU1_P1_TX_DN<5>";
101"P5E_CPU1_P1_TX_DN<4>";
102"P5E_CPU1_P1_TX_DN<3>";
103"P5E_CPU1_P1_TX_DN<2>";
104"P5E_CPU1_P1_TX_DN<1>";
105"P5E_CPU1_P1_TX_DN<0>";
106"P5E_CPU1_P1_TX_DN<8>";
107"P5E_CPU1_P0_TX_DP<3>";
108"P5E_CPU1_P0_TX_DN<6>";
109"P5E_CPU1_P0_TX_DN<3>";
110"P5E_CPU1_P0_TX_DP<4>";
111"P5E_CPU1_P0_TX_DP<1>";
112"P5E_CPU1_P0_TX_DP<6>";
113"P5E_CPU1_P0_TX_DN<1>";
114"P5E_CPU1_P0_TX_DN<7>";
115"P5E_CPU1_P0_TX_DN<4>";
116"P5E_CPU1_P0_TX_DP<2>";
117"P5E_CPU1_P0_TX_DP<5>";
118"P5E_CPU1_P0_TX_DP<7>";
119"P5E_CPU1_P0_TX_DN<5>";
120"P5E_CPU1_P0_TX_DN<2>";
121"P5E_CPU1_P0_TX_DP<12>";
122"P5E_CPU1_P0_TX_DP<9>";
123"P5E_CPU1_P0_TX_DP<15>";
124"P5E_CPU1_P0_TX_DN<10>";
125"P5E_CPU1_P0_TX_DN<13>";
126"P5E_CPU1_P0_TX_DP<13>";
127"P5E_CPU1_P0_TX_DP<10>";
128"P5E_CPU1_P0_TX_DN<14>";
129"P5E_CPU1_P0_TX_DN<8>";
130"P5E_CPU1_P0_TX_DN<11>";
131"P5E_CPU1_P0_TX_DP<8>";
132"P5E_CPU1_P0_TX_DP<14>";
133"P5E_CPU1_P0_TX_DP<11>";
134"P5E_CPU1_P0_TX_DN<9>";
135"P5E_CPU1_P0_TX_DN<15>";
136"P5E_CPU1_P0_TX_DN<12>";
%"GENOA_SP5"
"15","(-4700,4750)","0","pure_quanta","I147";
;
LOCATION"U26"
$SEC"15"
CDS_SEC"15"
MATERIAL"IO"
PART_NUMBER"DGA^6000030"
PART_TYPE"SMLF"
VALUE"SOCKET6096_13568-001"
CDS_LIB"pure_quanta"
NEEDS_NO_SIZE"TRUE"
CDS_LMAN_SYM_OUTLINE"-1100,950,1100,-950";
"P0_RXP11||SATA13_RXP"
$PN"BU43"49;
"P0_TXP12||SATA14_TXP"
$PN"CN44"107;
"P0_TXP15||SATA17_TXP"
$PN"CM41"96;
"P0_RXN11||SATA13_RXN"
$PN"BU44"50;
"P0_RXN14||SATA16_RXN"
$PN"BV41"51;
"P0_TXN15||SATA17_TXN"
$PN"CM40"97;
"P0_RXP13||SATA15_RXP"
$PN"CB40"52;
"P0_TXN9||SATA11_TXN"
$PN"CN46"108;
"P0_TXN12||SATA14_TXN"
$PN"CN43"109;
"P0_RXP10||SATA12_RXP"
$PN"CA43"53;
"P0_RXN9||SATA11_RXN"
$PN"BW44"54;
"P0_TXP11||SATA13_TXP"
$PN"CU44"110;
"P0_TXP14||SATA16_TXP"
$PN"CP41"111;
"P0_RXN10||SATA12_RXN"
$PN"CA44"55;
"P0_RXN13||SATA15_RXN"
$PN"CB41"56;
"P0_TXP9||SATA11_TXP"
$PN"CN47"112;
"P0_RXP9||SATA11_RXP"
$PN"BW43"57;
"P0_TXN14||SATA16_TXN"
$PN"CP40"113;
"P0_RXP12||SATA14_RXP"
$PN"BY40"58;
"P0_RXP15||SATA17_RXP"
$PN"BT40"17;
"P0_TXN8||SATA10_TXN"
$PN"CU46"114;
"P0_TXN11||SATA13_TXN"
$PN"CU43"115;
"P0_RXN8||SATA10_RXN"
$PN"BU47"59;
"P0_TXP13||SATA15_TXP"
$PN"CT41"116;
"P0_TXP10||SATA12_TXP"
$PN"CR44"117;
"P0_RXN15||SATA17_RXN"
$PN"BT41"18;
"P0_TXP8||SATA10_TXP"
$PN"CU47"118;
"P0_RXN12||SATA14_RXN"
$PN"BY41"60;
"P0_RXP8||SATA10_RXP"
$PN"BU46"61;
"P0_RXP14||SATA16_RXP"
$PN"BV40"62;
"P0_TXN10||SATA12_TXN"
$PN"CR43"119;
"P0_TXN13||SATA15_TXN"
$PN"CT40"120;
"P0_TXP3||SATA03_TXP"
$PN"CN50"121;
"P0_TXP6||SATA06_TXP"
$PN"CL50"122;
"P0_TXP0||SATA00_TXP"
$PN"CN53"123;
"P0_RXP3||SATA03_RXP"
$PN"BW49"11;
"P0_RXP6||SATA06_RXP"
$PN"BW46"63;
"P0_TXN5||SATA05_TXN"
$PN"CU49"124;
"P0_RXP0||SATA00_RXP"
$PN"BW52"64;
"P0_TXN2||SATA02_TXN"
$PN"CL52"125;
"P0_RXN2||SATA02_RXN"
$PN"BU53"65;
"P0_RXN5||SATA05_RXN"
$PN"BU50"15;
"P0_TXP2||SATA02_TXP"
$PN"CL53"126;
"P0_TXP5||SATA05_TXP"
$PN"CU50"127;
"P0_RXP5||SATA05_RXP"
$PN"BU49"66;
"P0_RXP2||SATA02_RXP"
$PN"BU52"67;
"P0_TXN1||SATA01_TXN"
$PN"CR52"128;
"P0_TXN7||SATA07_TXN"
$PN"CR46"129;
"P0_TXN4||SATA04_TXN"
$PN"CR49"130;
"P0_RXN7||SATA07_RXN"
$PN"CA47"68;
"P0_RXN1||SATA01_RXN"
$PN"CA53"69;
"P0_RXN4||SATA04_RXN"
$PN"CA50"14;
"P0_TXP7||SATA07_TXP"
$PN"CR47"131;
"P0_TXP1||SATA01_TXP"
$PN"CR53"132;
"P0_TXP4||SATA04_TXP"
$PN"CR50"133;
"P0_RXP4||SATA04_RXP"
$PN"CA49"13;
"P0_RXP7||SATA07_RXP"
$PN"CA46"70;
"P0_TXN6||SATA06_TXN"
$PN"CL49"134;
"P0_RXP1||SATA01_RXP"
$PN"CA52"71;
"P0_TXN0||SATA00_TXN"
$PN"CN52"135;
"P0_TXN3||SATA03_TXN"
$PN"CN49"136;
"P0_RXN3||SATA03_RXN"
$PN"BW50"12;
"P0_RXN6||SATA06_RXN"
$PN"BW47"16;
"P0_RXN0||SATA00_RXN"
$PN"BW53"72;
%"GENOA_SP5"
"16","(-4700,2100)","0","pure_quanta","I148";
;
LOCATION"U26"
$SEC"16"
CDS_SEC"16"
MATERIAL"IO"
VALUE"SOCKET6096_13568-001"
PART_NUMBER"DGA^6000030"
PART_TYPE"SMLF"
NEEDS_NO_SIZE"TRUE"
CDS_LMAN_SYM_OUTLINE"-1100,950,1100,-950"
CDS_LIB"pure_quanta";
"P1_RXN6"
$PN"CE47"9;
"P1_RXN5"
$PN"CC50"19;
"P1_RXP7"
$PN"CG46"20;
"P1_TXN7"
$PN"DA46"98;
"P1_RXN4"
$PN"CG50"21;
"P1_RXP6"
$PN"CE46"10;
"P1_TXN6"
$PN"CW49"99;
"P1_RXN3"
$PN"CE50"22;
"P1_RXP5"
$PN"CC49"23;
"P1_TXN5"
$PN"DC49"100;
"P1_TXP7"
$PN"DA47"87;
"P1_RXN2"
$PN"CC53"24;
"P1_RXP4"
$PN"CG49"25;
"P1_TXN4"
$PN"DA49"101;
"P1_TXP6"
$PN"CW50"88;
"P1_RXN1"
$PN"CG53"26;
"P1_RXP3"
$PN"CE49"27;
"P1_TXN3"
$PN"CW52"102;
"P1_TXP5"
$PN"DC50"89;
"P1_RXN0"
$PN"CE53"28;
"P1_RXP2"
$PN"CC52"29;
"P1_TXN2"
$PN"DC52"103;
"P1_TXP4"
$PN"DA50"90;
"P1_RXP1"
$PN"CG52"30;
"P1_TXN1"
$PN"DA52"104;
"P1_TXP3"
$PN"CW53"92;
"P1_RXP0"
$PN"CE52"31;
"P1_TXN0"
$PN"CU52"105;
"P1_TXP2"
$PN"DC53"93;
"P1_TXP1"
$PN"DA53"94;
"P1_TXP0"
$PN"CU53"95;
"P1_RXN7"
$PN"CG47"32;
"P1_TXN15"
$PN"CV40"80;
"P1_TXP15"
$PN"CV41"73;
"P1_TXN14"
$PN"CY40"81;
"P1_TXP14"
$PN"CY41"74;
"P1_TXN13"
$PN"DB40"82;
"P1_TXP13"
$PN"DB41"75;
"P1_TXN12"
$PN"CW43"83;
"P1_TXP12"
$PN"CW44"76;
"P1_TXN11"
$PN"DC43"84;
"P1_TXP11"
$PN"DC44"77;
"P1_TXN10"
$PN"DA43"85;
"P1_TXP10"
$PN"DA44"78;
"P1_TXN9"
$PN"CW46"86;
"P1_TXP9"
$PN"CW47"79;
"P1_TXN8"
$PN"DC46"106;
"P1_TXP8"
$PN"DC47"91;
"P1_RXN15"
$PN"CD41"33;
"P1_RXP15"
$PN"CD40"34;
"P1_RXN14"
$PN"CF41"35;
"P1_RXP14"
$PN"CF40"36;
"P1_RXN13"
$PN"CH41"37;
"P1_RXP13"
$PN"CH40"38;
"P1_RXN12"
$PN"CC44"39;
"P1_RXP12"
$PN"CC43"40;
"P1_RXN11"
$PN"CJ44"41;
"P1_RXP11"
$PN"CJ43"42;
"P1_RXN10"
$PN"CG44"43;
"P1_RXP10"
$PN"CG43"44;
"P1_RXN9"
$PN"CE44"45;
"P1_RXP9"
$PN"CE43"46;
"P1_RXN8"
$PN"CC47"47;
"P1_RXP8"
$PN"CC46"48;
%"TAP"
"6","(-2875,2850)","2","mstr_standard","I186";
;
CDS_LIB"mstr_standard"
BOM_COST"IO_SLOT"
BODY_TYPE"PLUMBING"
HDL_TAP"TRUE"
ROOM"RISER1";
"B \NAC \NWC"3;
"S \NAC"
BN"0"105;
%"TAP"
"6","(-2875,2750)","2","mstr_standard","I187";
;
BOM_COST"IO_SLOT"
CDS_LIB"mstr_standard"
BODY_TYPE"PLUMBING"
HDL_TAP"TRUE"
ROOM"RISER1";
"B \NAC \NWC"3;
"S \NAC"
BN"1"104;
%"TAP"
"6","(-2875,2650)","2","standard","I188";
;
BOM_COST"IO_SLOT"
CDS_LIB"standard"
BODY_TYPE"PLUMBING"
HDL_TAP"TRUE"
ROOM"RISER1";
"B \NAC \NWC"3;
"S \NAC"
BN"2"103;
%"TAP"
"6","(-2875,2450)","2","standard","I189";
;
BOM_COST"IO_SLOT"
CDS_LIB"standard"
BODY_TYPE"PLUMBING"
HDL_TAP"TRUE"
ROOM"RISER1";
"B \NAC \NWC"3;
"S \NAC"
BN"4"101;
%"TAP"
"6","(-2875,2550)","2","standard","I190";
;
BOM_COST"IO_SLOT"
CDS_LIB"standard"
BODY_TYPE"PLUMBING"
HDL_TAP"TRUE"
ROOM"RISER1";
"B \NAC \NWC"3;
"S \NAC"
BN"3"102;
%"TAP"
"6","(-2875,2350)","2","standard","I191";
;
BOM_COST"IO_SLOT"
CDS_LIB"standard"
BODY_TYPE"PLUMBING"
HDL_TAP"TRUE"
ROOM"RISER1";
"B \NAC \NWC"3;
"S \NAC"
BN"5"100;
%"TAP"
"6","(-2875,2250)","2","standard","I192";
;
BOM_COST"IO_SLOT"
CDS_LIB"standard"
BODY_TYPE"PLUMBING"
HDL_TAP"TRUE"
ROOM"RISER1";
"B \NAC \NWC"3;
"S \NAC"
BN"6"99;
%"TAP"
"6","(-2875,2050)","2","standard","I193";
;
BOM_COST"IO_SLOT"
CDS_LIB"standard"
BODY_TYPE"PLUMBING"
HDL_TAP"TRUE"
ROOM"RISER1";
"B \NAC \NWC"3;
"S \NAC"
BN"8"106;
%"TAP"
"6","(-2875,2150)","2","standard","I194";
;
BOM_COST"IO_SLOT"
CDS_LIB"standard"
BODY_TYPE"PLUMBING"
HDL_TAP"TRUE"
ROOM"RISER1";
"B \NAC \NWC"3;
"S \NAC"
BN"7"98;
%"TAP"
"6","(-3025,2900)","2","mstr_standard","I196";
;
BOM_COST"IO_SLOT"
CDS_LIB"mstr_standard"
BODY_TYPE"PLUMBING"
HDL_TAP"TRUE"
ROOM"RISER1";
"B \NAC \NWC"4;
"S \NAC"
BN"0"95;
%"TAP"
"6","(-3025,2700)","2","standard","I197";
;
BOM_COST"IO_SLOT"
CDS_LIB"standard"
BODY_TYPE"PLUMBING"
HDL_TAP"TRUE"
ROOM"RISER1";
"B \NAC \NWC"4;
"S \NAC"
BN"2"93;
%"TAP"
"6","(-3025,2800)","2","mstr_standard","I198";
;
BOM_COST"IO_SLOT"
CDS_LIB"mstr_standard"
BODY_TYPE"PLUMBING"
HDL_TAP"TRUE"
ROOM"RISER1";
"B \NAC \NWC"4;
"S \NAC"
BN"1"94;
%"TAP"
"6","(-3025,2600)","2","standard","I199";
;
BOM_COST"IO_SLOT"
CDS_LIB"standard"
BODY_TYPE"PLUMBING"
HDL_TAP"TRUE"
ROOM"RISER1";
"B \NAC \NWC"4;
"S \NAC"
BN"3"92;
%"TAP"
"6","(-3025,2500)","2","standard","I200";
;
BOM_COST"IO_SLOT"
CDS_LIB"standard"
BODY_TYPE"PLUMBING"
HDL_TAP"TRUE"
ROOM"RISER1";
"B \NAC \NWC"4;
"S \NAC"
BN"4"90;
%"TAP"
"6","(-3025,2400)","2","standard","I201";
;
BOM_COST"IO_SLOT"
CDS_LIB"standard"
BODY_TYPE"PLUMBING"
HDL_TAP"TRUE"
ROOM"RISER1";
"B \NAC \NWC"4;
"S \NAC"
BN"5"89;
%"TAP"
"6","(-3025,2300)","2","standard","I202";
;
BOM_COST"IO_SLOT"
CDS_LIB"standard"
BODY_TYPE"PLUMBING"
HDL_TAP"TRUE"
ROOM"RISER1";
"B \NAC \NWC"4;
"S \NAC"
BN"6"88;
%"TAP"
"6","(-3025,2200)","2","standard","I203";
;
BOM_COST"IO_SLOT"
CDS_LIB"standard"
BODY_TYPE"PLUMBING"
HDL_TAP"TRUE"
ROOM"RISER1";
"B \NAC \NWC"4;
"S \NAC"
BN"7"87;
%"TAP"
"6","(-3025,2100)","2","standard","I204";
;
BOM_COST"IO_SLOT"
CDS_LIB"standard"
BODY_TYPE"PLUMBING"
HDL_TAP"TRUE"
ROOM"RISER1";
"B \NAC \NWC"4;
"S \NAC"
BN"8"91;
%"TAP"
"6","(-2875,1950)","2","standard","I205";
;
BOM_COST"IO_SLOT"
CDS_LIB"standard"
BODY_TYPE"PLUMBING"
HDL_TAP"TRUE"
ROOM"RISER1";
"B \NAC \NWC"3;
"S \NAC"
BN"9"86;
%"TAP"
"6","(-2875,1850)","2","standard","I206";
;
BOM_COST"IO_SLOT"
CDS_LIB"standard"
BODY_TYPE"PLUMBING"
HDL_TAP"TRUE"
ROOM"RISER1";
"B \NAC \NWC"3;
"S \NAC"
BN"10"85;
%"TAP"
"6","(-2875,1750)","2","standard","I207";
;
BOM_COST"IO_SLOT"
CDS_LIB"standard"
BODY_TYPE"PLUMBING"
HDL_TAP"TRUE"
ROOM"RISER1";
"B \NAC \NWC"3;
"S \NAC"
BN"11"84;
%"TAP"
"6","(-2875,1550)","2","standard","I208";
;
BOM_COST"IO_SLOT"
CDS_LIB"standard"
BODY_TYPE"PLUMBING"
HDL_TAP"TRUE"
ROOM"RISER1";
"B \NAC \NWC"3;
"S \NAC"
BN"13"82;
%"TAP"
"6","(-2875,1650)","2","standard","I209";
;
BOM_COST"IO_SLOT"
CDS_LIB"standard"
BODY_TYPE"PLUMBING"
HDL_TAP"TRUE"
ROOM"RISER1";
"B \NAC \NWC"3;
"S \NAC"
BN"12"83;
%"TAP"
"6","(-2875,1450)","2","standard","I210";
;
CDS_LIB"standard"
BOM_COST"IO_SLOT"
BODY_TYPE"PLUMBING"
HDL_TAP"TRUE"
ROOM"RISER1";
"B \NAC \NWC"3;
"S \NAC"
BN"14"81;
%"TAP"
"6","(-2875,1350)","2","standard","I211";
;
BOM_COST"IO_SLOT"
CDS_LIB"standard"
BODY_TYPE"PLUMBING"
HDL_TAP"TRUE"
ROOM"RISER1";
"B \NAC \NWC"3;
"S \NAC"
BN"15"80;
%"TAP"
"6","(-3025,2000)","2","standard","I212";
;
BOM_COST"IO_SLOT"
CDS_LIB"standard"
BODY_TYPE"PLUMBING"
HDL_TAP"TRUE"
ROOM"RISER1";
"B \NAC \NWC"4;
"S \NAC"
BN"9"79;
%"TAP"
"6","(-3025,1900)","2","standard","I213";
;
BOM_COST"IO_SLOT"
CDS_LIB"standard"
BODY_TYPE"PLUMBING"
HDL_TAP"TRUE"
ROOM"RISER1";
"B \NAC \NWC"4;
"S \NAC"
BN"10"78;
%"TAP"
"6","(-3025,1800)","2","standard","I214";
;
BOM_COST"IO_SLOT"
CDS_LIB"standard"
BODY_TYPE"PLUMBING"
HDL_TAP"TRUE"
ROOM"RISER1";
"B \NAC \NWC"4;
"S \NAC"
BN"11"77;
%"TAP"
"6","(-3025,1700)","2","standard","I215";
;
BOM_COST"IO_SLOT"
CDS_LIB"standard"
BODY_TYPE"PLUMBING"
HDL_TAP"TRUE"
ROOM"RISER1";
"B \NAC \NWC"4;
"S \NAC"
BN"12"76;
%"TAP"
"6","(-3025,1600)","2","standard","I216";
;
BOM_COST"IO_SLOT"
CDS_LIB"standard"
BODY_TYPE"PLUMBING"
HDL_TAP"TRUE"
ROOM"RISER1";
"B \NAC \NWC"4;
"S \NAC"
BN"13"75;
%"TAP"
"6","(-3025,1500)","2","standard","I217";
;
BOM_COST"IO_SLOT"
CDS_LIB"standard"
BODY_TYPE"PLUMBING"
HDL_TAP"TRUE"
ROOM"RISER1";
"B \NAC \NWC"4;
"S \NAC"
BN"14"74;
%"TAP"
"6","(-3025,1400)","2","standard","I218";
;
BOM_COST"IO_SLOT"
CDS_LIB"standard"
BODY_TYPE"PLUMBING"
HDL_TAP"TRUE"
ROOM"RISER1";
"B \NAC \NWC"4;
"S \NAC"
BN"15"73;
%"TAP"
"6","(-6450,5550)","0","mstr_standard","I219";
;
CDS_LIB"mstr_standard"
BODY_TYPE"PLUMBING"
HDL_TAP"TRUE";
"B \NAC \NWC"5;
"S \NAC"
BN"15"64;
%"TAP"
"6","(-6450,5350)","0","mstr_standard","I220";
;
CDS_LIB"mstr_standard"
BODY_TYPE"PLUMBING"
HDL_TAP"TRUE";
"B \NAC \NWC"5;
"S \NAC"
BN"13"67;
%"TAP"
"6","(-6450,5450)","0","mstr_standard","I221";
;
CDS_LIB"mstr_standard"
BODY_TYPE"PLUMBING"
HDL_TAP"TRUE";
"B \NAC \NWC"5;
"S \NAC"
BN"14"71;
%"TAP"
"6","(-6450,5250)","0","standard","I222";
;
CDS_LIB"standard"
BODY_TYPE"PLUMBING"
HDL_TAP"TRUE";
"B \NAC \NWC"5;
"S \NAC"
BN"12"11;
%"TAP"
"6","(-6450,5150)","0","standard","I223";
;
CDS_LIB"standard"
BODY_TYPE"PLUMBING"
HDL_TAP"TRUE";
"B \NAC \NWC"5;
"S \NAC"
BN"11"13;
%"TAP"
"6","(-6450,5050)","0","standard","I228";
;
CDS_LIB"standard"
BODY_TYPE"PLUMBING"
HDL_TAP"TRUE";
"B \NAC \NWC"5;
"S \NAC"
BN"10"66;
%"TAP"
"6","(-6450,4850)","0","standard","I229";
;
CDS_LIB"standard"
BODY_TYPE"PLUMBING"
HDL_TAP"TRUE";
"B \NAC \NWC"5;
"S \NAC"
BN"8"70;
%"TAP"
"6","(-6450,4950)","0","standard","I230";
;
CDS_LIB"standard"
BODY_TYPE"PLUMBING"
HDL_TAP"TRUE";
"B \NAC \NWC"5;
"S \NAC"
BN"9"63;
%"TAP"
"6","(-6450,4750)","0","standard","I231";
;
CDS_LIB"standard"
BODY_TYPE"PLUMBING"
HDL_TAP"TRUE";
"B \NAC \NWC"5;
"S \NAC"
BN"7"61;
%"TAP"
"6","(-6450,4650)","0","standard","I232";
;
CDS_LIB"standard"
BODY_TYPE"PLUMBING"
HDL_TAP"TRUE";
"B \NAC \NWC"5;
"S \NAC"
BN"6"57;
%"TAP"
"6","(-6450,4450)","0","standard","I238";
;
CDS_LIB"standard"
BODY_TYPE"PLUMBING"
HDL_TAP"TRUE";
"B \NAC \NWC"5;
"S \NAC"
BN"4"49;
%"TAP"
"6","(-6450,4550)","0","standard","I239";
;
CDS_LIB"standard"
BODY_TYPE"PLUMBING"
HDL_TAP"TRUE";
"B \NAC \NWC"5;
"S \NAC"
BN"5"53;
%"TAP"
"6","(-6450,4350)","0","standard","I240";
;
CDS_LIB"standard"
BODY_TYPE"PLUMBING"
HDL_TAP"TRUE";
"B \NAC \NWC"5;
"S \NAC"
BN"3"58;
%"TAP"
"6","(-6450,4250)","0","standard","I241";
;
CDS_LIB"standard"
BODY_TYPE"PLUMBING"
HDL_TAP"TRUE";
"B \NAC \NWC"5;
"S \NAC"
BN"2"52;
%"TAP"
"6","(-6450,4150)","0","standard","I242";
;
CDS_LIB"standard"
BODY_TYPE"PLUMBING"
HDL_TAP"TRUE";
"B \NAC \NWC"5;
"S \NAC"
BN"1"62;
%"TAP"
"6","(-6450,4050)","0","standard","I253";
;
CDS_LIB"standard"
BODY_TYPE"PLUMBING"
HDL_TAP"TRUE";
"B \NAC \NWC"5;
"S \NAC"
BN"0"17;
%"TAP"
"6","(-6450,2600)","0","standard","I255";
;
CDS_LIB"standard"
BODY_TYPE"PLUMBING"
HDL_TAP"TRUE";
"B \NAC \NWC"7;
"S \NAC"
BN"3"27;
%"TAP"
"6","(-6450,2700)","0","mstr_standard","I256";
;
CDS_LIB"mstr_standard"
BODY_TYPE"PLUMBING"
HDL_TAP"TRUE";
"B \NAC \NWC"7;
"S \NAC"
BN"2"29;
%"TAP"
"6","(-6450,2900)","0","mstr_standard","I257";
;
CDS_LIB"mstr_standard"
BODY_TYPE"PLUMBING"
HDL_TAP"TRUE";
"B \NAC \NWC"7;
"S \NAC"
BN"0"31;
%"TAP"
"6","(-6450,2800)","0","mstr_standard","I258";
;
CDS_LIB"mstr_standard"
BODY_TYPE"PLUMBING"
HDL_TAP"TRUE";
"B \NAC \NWC"7;
"S \NAC"
BN"1"30;
%"TAP"
"6","(-6600,2850)","0","mstr_standard","I259";
;
CDS_LIB"mstr_standard"
BODY_TYPE"PLUMBING"
HDL_TAP"TRUE";
"B \NAC \NWC"8;
"S \NAC"
BN"0"28;
%"TAP"
"6","(-6600,2750)","0","mstr_standard","I260";
;
CDS_LIB"mstr_standard"
BODY_TYPE"PLUMBING"
HDL_TAP"TRUE";
"B \NAC \NWC"8;
"S \NAC"
BN"1"26;
%"TAP"
"6","(-6600,2650)","0","standard","I261";
;
CDS_LIB"standard"
BODY_TYPE"PLUMBING"
HDL_TAP"TRUE";
"B \NAC \NWC"8;
"S \NAC"
BN"2"24;
%"TAP"
"6","(-6450,2100)","0","standard","I262";
;
CDS_LIB"standard"
BODY_TYPE"PLUMBING"
HDL_TAP"TRUE";
"B \NAC \NWC"7;
"S \NAC"
BN"8"48;
%"TAP"
"6","(-6450,2200)","0","standard","I263";
;
CDS_LIB"standard"
BODY_TYPE"PLUMBING"
HDL_TAP"TRUE";
"B \NAC \NWC"7;
"S \NAC"
BN"7"20;
%"TAP"
"6","(-6450,2300)","0","standard","I264";
;
CDS_LIB"standard"
BODY_TYPE"PLUMBING"
HDL_TAP"TRUE";
"B \NAC \NWC"7;
"S \NAC"
BN"6"10;
%"TAP"
"6","(-6450,2500)","0","standard","I265";
;
CDS_LIB"standard"
BODY_TYPE"PLUMBING"
HDL_TAP"TRUE";
"B \NAC \NWC"7;
"S \NAC"
BN"4"25;
%"TAP"
"6","(-6450,2400)","0","standard","I266";
;
CDS_LIB"standard"
BODY_TYPE"PLUMBING"
HDL_TAP"TRUE";
"B \NAC \NWC"7;
"S \NAC"
BN"5"23;
%"TAP"
"6","(-6600,2550)","0","standard","I267";
;
CDS_LIB"standard"
BODY_TYPE"PLUMBING"
HDL_TAP"TRUE";
"B \NAC \NWC"8;
"S \NAC"
BN"3"22;
%"TAP"
"6","(-6600,2450)","0","standard","I268";
;
CDS_LIB"standard"
BODY_TYPE"PLUMBING"
HDL_TAP"TRUE";
"B \NAC \NWC"8;
"S \NAC"
BN"4"21;
%"TAP"
"6","(-6600,2350)","0","standard","I269";
;
CDS_LIB"standard"
BODY_TYPE"PLUMBING"
HDL_TAP"TRUE";
"B \NAC \NWC"8;
"S \NAC"
BN"5"19;
%"TAP"
"6","(-6600,2150)","0","standard","I270";
;
CDS_LIB"standard"
BODY_TYPE"PLUMBING"
HDL_TAP"TRUE";
"B \NAC \NWC"8;
"S \NAC"
BN"7"32;
%"TAP"
"6","(-6600,2250)","0","standard","I271";
;
CDS_LIB"standard"
BODY_TYPE"PLUMBING"
HDL_TAP"TRUE";
"B \NAC \NWC"8;
"S \NAC"
BN"6"9;
%"TAP"
"6","(-6600,2050)","0","standard","I272";
;
CDS_LIB"standard"
BODY_TYPE"PLUMBING"
HDL_TAP"TRUE";
"B \NAC \NWC"8;
"S \NAC"
BN"8"47;
%"TAP"
"6","(-6450,1800)","0","standard","I275";
;
CDS_LIB"standard"
BODY_TYPE"PLUMBING"
HDL_TAP"TRUE";
"B \NAC \NWC"7;
"S \NAC"
BN"11"42;
%"TAP"
"6","(-6450,1900)","0","standard","I276";
;
CDS_LIB"standard"
BODY_TYPE"PLUMBING"
HDL_TAP"TRUE";
"B \NAC \NWC"7;
"S \NAC"
BN"10"44;
%"TAP"
"6","(-6450,2000)","0","standard","I277";
;
CDS_LIB"standard"
BODY_TYPE"PLUMBING"
HDL_TAP"TRUE";
"B \NAC \NWC"7;
"S \NAC"
BN"9"46;
%"TAP"
"6","(-6450,1700)","0","standard","I278";
;
CDS_LIB"standard"
BODY_TYPE"PLUMBING"
HDL_TAP"TRUE";
"B \NAC \NWC"7;
"S \NAC"
BN"12"40;
%"TAP"
"6","(-6450,1600)","0","standard","I279";
;
CDS_LIB"standard"
BODY_TYPE"PLUMBING"
HDL_TAP"TRUE";
"B \NAC \NWC"7;
"S \NAC"
BN"13"38;
%"TAP"
"6","(-6600,1950)","0","standard","I280";
;
CDS_LIB"standard"
BODY_TYPE"PLUMBING"
HDL_TAP"TRUE";
"B \NAC \NWC"8;
"S \NAC"
BN"9"45;
%"TAP"
"6","(-6600,1850)","0","standard","I281";
;
CDS_LIB"standard"
BODY_TYPE"PLUMBING"
HDL_TAP"TRUE";
"B \NAC \NWC"8;
"S \NAC"
BN"10"43;
%"TAP"
"6","(-6600,1750)","0","standard","I282";
;
CDS_LIB"standard"
BODY_TYPE"PLUMBING"
HDL_TAP"TRUE";
"B \NAC \NWC"8;
"S \NAC"
BN"11"41;
%"TAP"
"6","(-6600,1650)","0","standard","I283";
;
CDS_LIB"standard"
BODY_TYPE"PLUMBING"
HDL_TAP"TRUE";
"B \NAC \NWC"8;
"S \NAC"
BN"12"39;
%"TAP"
"6","(-6600,1550)","0","standard","I284";
;
CDS_LIB"standard"
BODY_TYPE"PLUMBING"
HDL_TAP"TRUE";
"B \NAC \NWC"8;
"S \NAC"
BN"13"37;
%"TAP"
"6","(-6450,1500)","0","standard","I285";
;
CDS_LIB"standard"
BODY_TYPE"PLUMBING"
HDL_TAP"TRUE";
"B \NAC \NWC"7;
"S \NAC"
BN"14"36;
%"TAP"
"6","(-6450,1400)","0","standard","I286";
;
CDS_LIB"standard"
BODY_TYPE"PLUMBING"
HDL_TAP"TRUE";
"B \NAC \NWC"7;
"S \NAC"
BN"15"34;
%"TAP"
"6","(-6600,1350)","0","standard","I287";
;
CDS_LIB"standard"
BODY_TYPE"PLUMBING"
HDL_TAP"TRUE";
"B \NAC \NWC"8;
"S \NAC"
BN"15"33;
%"TAP"
"6","(-6600,1450)","0","standard","I288";
;
CDS_LIB"standard"
BODY_TYPE"PLUMBING"
HDL_TAP"TRUE";
"B \NAC \NWC"8;
"S \NAC"
BN"14"35;
%"TAP"
"6","(-2950,5550)","2","mstr_standard","I291";
;
CDS_LIB"mstr_standard"
BOM_COST"IO_SLOT"
BODY_TYPE"PLUMBING"
HDL_TAP"TRUE"
ROOM"RISER1";
"B \NAC \NWC"1;
"S \NAC"
BN"15"123;
%"TAP"
"6","(-2950,5350)","2","standard","I295";
;
CDS_LIB"standard"
BOM_COST"IO_SLOT"
BODY_TYPE"PLUMBING"
HDL_TAP"TRUE"
ROOM"RISER1";
"B \NAC \NWC"1;
"S \NAC"
BN"13"126;
%"TAP"
"6","(-2950,5450)","2","mstr_standard","I296";
;
CDS_LIB"mstr_standard"
BOM_COST"IO_SLOT"
BODY_TYPE"PLUMBING"
HDL_TAP"TRUE"
ROOM"RISER1";
"B \NAC \NWC"1;
"S \NAC"
BN"14"132;
%"TAP"
"6","(-2950,5150)","2","standard","I299";
;
CDS_LIB"standard"
BOM_COST"IO_SLOT"
BODY_TYPE"PLUMBING"
HDL_TAP"TRUE"
ROOM"RISER1";
"B \NAC \NWC"1;
"S \NAC"
BN"11"133;
%"TAP"
"6","(-2950,5250)","2","standard","I300";
;
CDS_LIB"standard"
BOM_COST"IO_SLOT"
BODY_TYPE"PLUMBING"
HDL_TAP"TRUE"
ROOM"RISER1";
"B \NAC \NWC"1;
"S \NAC"
BN"12"121;
%"TAP"
"6","(-2950,5050)","2","standard","I301";
;
CDS_LIB"standard"
BOM_COST"IO_SLOT"
BODY_TYPE"PLUMBING"
HDL_TAP"TRUE"
ROOM"RISER1";
"B \NAC \NWC"1;
"S \NAC"
BN"10"127;
%"TAP"
"6","(-2950,4950)","2","standard","I305";
;
CDS_LIB"standard"
BOM_COST"IO_SLOT"
BODY_TYPE"PLUMBING"
HDL_TAP"TRUE"
ROOM"RISER1";
"B \NAC \NWC"1;
"S \NAC"
BN"9"122;
%"TAP"
"6","(-2950,4850)","2","standard","I306";
;
CDS_LIB"standard"
BOM_COST"IO_SLOT"
BODY_TYPE"PLUMBING"
HDL_TAP"TRUE"
ROOM"RISER1";
"B \NAC \NWC"1;
"S \NAC"
BN"8"131;
%"TAP"
"6","(-2950,4750)","2","standard","I307";
;
CDS_LIB"standard"
BOM_COST"IO_SLOT"
BODY_TYPE"PLUMBING"
HDL_TAP"TRUE"
ROOM"RISER1";
"B \NAC \NWC"1;
"S \NAC"
BN"7"118;
%"TAP"
"6","(-2950,4650)","2","standard","I311";
;
CDS_LIB"standard"
BOM_COST"IO_SLOT"
BODY_TYPE"PLUMBING"
HDL_TAP"TRUE"
ROOM"RISER1";
"B \NAC \NWC"1;
"S \NAC"
BN"6"112;
%"TAP"
"6","(-2950,4550)","2","standard","I312";
;
CDS_LIB"standard"
BOM_COST"IO_SLOT"
BODY_TYPE"PLUMBING"
HDL_TAP"TRUE"
ROOM"RISER1";
"B \NAC \NWC"1;
"S \NAC"
BN"5"117;
%"TAP"
"6","(-2950,4450)","2","standard","I315";
;
CDS_LIB"standard"
BOM_COST"IO_SLOT"
BODY_TYPE"PLUMBING"
HDL_TAP"TRUE"
ROOM"RISER1";
"B \NAC \NWC"1;
"S \NAC"
BN"4"110;
%"TAP"
"6","(-2950,4350)","2","standard","I316";
;
CDS_LIB"standard"
BOM_COST"IO_SLOT"
BODY_TYPE"PLUMBING"
HDL_TAP"TRUE"
ROOM"RISER1";
"B \NAC \NWC"1;
"S \NAC"
BN"3"107;
%"TAP"
"6","(-2950,4250)","2","standard","I317";
;
CDS_LIB"standard"
BOM_COST"IO_SLOT"
BODY_TYPE"PLUMBING"
HDL_TAP"TRUE"
ROOM"RISER1";
"B \NAC \NWC"1;
"S \NAC"
BN"2"116;
%"TAP"
"6","(-2950,4150)","2","standard","I321";
;
CDS_LIB"standard"
BOM_COST"IO_SLOT"
BODY_TYPE"PLUMBING"
HDL_TAP"TRUE"
ROOM"RISER1";
"B \NAC \NWC"1;
"S \NAC"
BN"1"111;
%"TAP"
"6","(-2950,4050)","2","standard","I322";
;
CDS_LIB"standard"
BOM_COST"IO_SLOT"
BODY_TYPE"PLUMBING"
HDL_TAP"TRUE"
ROOM"RISER1";
"B \NAC \NWC"1;
"S \NAC"
BN"0"96;
%"TAP"
"6","(-6600,5500)","0","mstr_standard","I323";
;
CDS_LIB"mstr_standard"
BODY_TYPE"PLUMBING"
HDL_TAP"TRUE";
"B \NAC \NWC"6;
"S \NAC"
BN"15"72;
%"TAP"
"6","(-6600,5400)","0","mstr_standard","I324";
;
CDS_LIB"mstr_standard"
BODY_TYPE"PLUMBING"
HDL_TAP"TRUE";
"B \NAC \NWC"6;
"S \NAC"
BN"14"69;
%"TAP"
"6","(-6600,5300)","0","standard","I325";
;
CDS_LIB"standard"
BODY_TYPE"PLUMBING"
HDL_TAP"TRUE";
"B \NAC \NWC"6;
"S \NAC"
BN"13"65;
%"TAP"
"6","(-6600,5200)","0","standard","I326";
;
CDS_LIB"standard"
BODY_TYPE"PLUMBING"
HDL_TAP"TRUE";
"B \NAC \NWC"6;
"S \NAC"
BN"12"12;
%"TAP"
"6","(-6600,5100)","0","standard","I327";
;
CDS_LIB"standard"
BODY_TYPE"PLUMBING"
HDL_TAP"TRUE";
"B \NAC \NWC"6;
"S \NAC"
BN"11"14;
%"TAP"
"6","(-6600,5000)","0","standard","I328";
;
CDS_LIB"standard"
BODY_TYPE"PLUMBING"
HDL_TAP"TRUE";
"B \NAC \NWC"6;
"S \NAC"
BN"10"15;
%"TAP"
"6","(-6600,4800)","0","standard","I329";
;
CDS_LIB"standard"
BODY_TYPE"PLUMBING"
HDL_TAP"TRUE";
"B \NAC \NWC"6;
"S \NAC"
BN"8"68;
%"TAP"
"6","(-6600,4900)","0","standard","I330";
;
CDS_LIB"standard"
BODY_TYPE"PLUMBING"
HDL_TAP"TRUE";
"B \NAC \NWC"6;
"S \NAC"
BN"9"16;
%"TAP"
"6","(-6600,4700)","0","standard","I331";
;
CDS_LIB"standard"
BODY_TYPE"PLUMBING"
HDL_TAP"TRUE";
"B \NAC \NWC"6;
"S \NAC"
BN"7"59;
%"TAP"
"6","(-6600,4600)","0","standard","I332";
;
CDS_LIB"standard"
BODY_TYPE"PLUMBING"
HDL_TAP"TRUE";
"B \NAC \NWC"6;
"S \NAC"
BN"6"54;
%"TAP"
"6","(-6600,4400)","0","standard","I333";
;
CDS_LIB"standard"
BODY_TYPE"PLUMBING"
HDL_TAP"TRUE";
"B \NAC \NWC"6;
"S \NAC"
BN"4"50;
%"TAP"
"6","(-6600,4500)","0","standard","I334";
;
CDS_LIB"standard"
BODY_TYPE"PLUMBING"
HDL_TAP"TRUE";
"B \NAC \NWC"6;
"S \NAC"
BN"5"55;
%"TAP"
"6","(-6600,4300)","0","standard","I335";
;
CDS_LIB"standard"
BODY_TYPE"PLUMBING"
HDL_TAP"TRUE";
"B \NAC \NWC"6;
"S \NAC"
BN"3"60;
%"TAP"
"6","(-6600,4200)","0","standard","I336";
;
CDS_LIB"standard"
BODY_TYPE"PLUMBING"
HDL_TAP"TRUE";
"B \NAC \NWC"6;
"S \NAC"
BN"2"56;
%"TAP"
"6","(-6600,4100)","0","standard","I337";
;
CDS_LIB"standard"
BODY_TYPE"PLUMBING"
HDL_TAP"TRUE";
"B \NAC \NWC"6;
"S \NAC"
BN"1"51;
%"TAP"
"6","(-6600,4000)","0","standard","I338";
;
CDS_LIB"standard"
BODY_TYPE"PLUMBING"
HDL_TAP"TRUE";
"B \NAC \NWC"6;
"S \NAC"
BN"0"18;
%"TAP"
"6","(-2800,4400)","2","standard","I340";
;
CDS_LIB"standard"
BOM_COST"IO_SLOT"
BODY_TYPE"PLUMBING"
HDL_TAP"TRUE"
ROOM"RISER1";
"B \NAC \NWC"2;
"S \NAC"
BN"4"115;
%"TAP"
"6","(-2800,5500)","2","mstr_standard","I342";
;
BOM_COST"IO_SLOT"
CDS_LIB"mstr_standard"
BODY_TYPE"PLUMBING"
HDL_TAP"TRUE"
ROOM"RISER1";
"B \NAC \NWC"2;
"S \NAC"
BN"15"135;
%"TAP"
"6","(-2800,5400)","2","mstr_standard","I343";
;
CDS_LIB"mstr_standard"
BOM_COST"IO_SLOT"
BODY_TYPE"PLUMBING"
HDL_TAP"TRUE"
ROOM"RISER1";
"B \NAC \NWC"2;
"S \NAC"
BN"14"128;
%"TAP"
"6","(-2800,5300)","2","standard","I344";
;
CDS_LIB"standard"
BOM_COST"IO_SLOT"
BODY_TYPE"PLUMBING"
HDL_TAP"TRUE"
ROOM"RISER1";
"B \NAC \NWC"2;
"S \NAC"
BN"13"125;
%"TAP"
"6","(-2800,5200)","2","standard","I345";
;
CDS_LIB"standard"
BOM_COST"IO_SLOT"
BODY_TYPE"PLUMBING"
HDL_TAP"TRUE"
ROOM"RISER1";
"B \NAC \NWC"2;
"S \NAC"
BN"12"136;
%"TAP"
"6","(-2800,5100)","2","standard","I346";
;
CDS_LIB"standard"
BOM_COST"IO_SLOT"
BODY_TYPE"PLUMBING"
HDL_TAP"TRUE"
ROOM"RISER1";
"B \NAC \NWC"2;
"S \NAC"
BN"11"130;
%"TAP"
"6","(-2800,5000)","2","standard","I347";
;
CDS_LIB"standard"
BOM_COST"IO_SLOT"
BODY_TYPE"PLUMBING"
HDL_TAP"TRUE"
ROOM"RISER1";
"B \NAC \NWC"2;
"S \NAC"
BN"10"124;
%"TAP"
"6","(-2800,4900)","2","standard","I348";
;
CDS_LIB"standard"
BOM_COST"IO_SLOT"
BODY_TYPE"PLUMBING"
HDL_TAP"TRUE"
ROOM"RISER1";
"B \NAC \NWC"2;
"S \NAC"
BN"9"134;
%"TAP"
"6","(-2800,4700)","2","standard","I349";
;
CDS_LIB"standard"
BOM_COST"IO_SLOT"
BODY_TYPE"PLUMBING"
HDL_TAP"TRUE"
ROOM"RISER1";
"B \NAC \NWC"2;
"S \NAC"
BN"7"114;
%"TAP"
"6","(-2800,4800)","2","standard","I350";
;
CDS_LIB"standard"
BOM_COST"IO_SLOT"
BODY_TYPE"PLUMBING"
HDL_TAP"TRUE"
ROOM"RISER1";
"B \NAC \NWC"2;
"S \NAC"
BN"8"129;
%"TAP"
"6","(-2800,4600)","2","standard","I351";
;
CDS_LIB"standard"
BOM_COST"IO_SLOT"
BODY_TYPE"PLUMBING"
HDL_TAP"TRUE"
ROOM"RISER1";
"B \NAC \NWC"2;
"S \NAC"
BN"6"108;
%"TAP"
"6","(-2800,4500)","2","standard","I352";
;
CDS_LIB"standard"
BOM_COST"IO_SLOT"
BODY_TYPE"PLUMBING"
HDL_TAP"TRUE"
ROOM"RISER1";
"B \NAC \NWC"2;
"S \NAC"
BN"5"119;
%"TAP"
"6","(-2800,4300)","2","standard","I353";
;
CDS_LIB"standard"
BOM_COST"IO_SLOT"
BODY_TYPE"PLUMBING"
HDL_TAP"TRUE"
ROOM"RISER1";
"B \NAC \NWC"2;
"S \NAC"
BN"3"109;
%"TAP"
"6","(-2800,4200)","2","standard","I354";
;
CDS_LIB"standard"
BOM_COST"IO_SLOT"
BODY_TYPE"PLUMBING"
HDL_TAP"TRUE"
ROOM"RISER1";
"B \NAC \NWC"2;
"S \NAC"
BN"2"120;
%"TAP"
"6","(-2800,4100)","2","standard","I355";
;
BOM_COST"IO_SLOT"
CDS_LIB"standard"
BODY_TYPE"PLUMBING"
HDL_TAP"TRUE"
ROOM"RISER1";
"B \NAC \NWC"2;
"S \NAC"
BN"1"113;
%"TAP"
"6","(-2800,4000)","2","standard","I356";
;
CDS_LIB"standard"
BOM_COST"IO_SLOT"
BODY_TYPE"PLUMBING"
HDL_TAP"TRUE"
ROOM"RISER1";
"B \NAC \NWC"2;
"S \NAC"
BN"0"97;
END.
